# T6G (Grand Teton) — schematic parts with pin connectivity, parts 5935–6086 of 8303; source: Cadence DE-HDL packaged netlist (pstxprt.dat, pstxnet.dat, pstchip.dat)

R1211  Q_RES  0 5% CHIP  pkg 0201LF  page 186 : 1 = RST_SMB_RT_ROM_R1_N ; 2 = FM_SMB_RT_ROM_MUX5_SEL
R1212  Q_RES  1K 1% CHIP  pkg 0201LF  page 186 : 1 = GND ; 2 = RT_ROM_MUX3_OE_N
R1213  Q_RES  1K 1% CHIP  pkg 0201LF  page 186 : 1 = GND ; 2 = RT_ROM_MUX2_OE_N
R1214  Q_RES  1K 1% CHIP  pkg 0201LF  page 186 : 1 = GND ; 2 = RT_ROM_MUX4_OE_N
R1215  Q_RES  1K 1% CHIP  pkg 0201LF  page 186 : 1 = GND ; 2 = RT_ROM_MUX1_OE_N
R1216  Q_RES  1K 1% CHIP  pkg 0201LF  page 186 : 1 = GND ; 2 = RT_ROM_MUX7_OE_N
R1217  Q_RES  1K 1% CHIP  pkg 0201LF  page 186 : 1 = GND ; 2 = RT_ROM_MUX8_OE_N
R1218  Q_RES  1K 1% CHIP  pkg 0201LF  page 186 : 1 = GND ; 2 = RT_ROM_MUX6_OE_N
R1219  Q_RES  1K 1% CHIP  pkg 0201LF  page 186 : 1 = GND ; 2 = RT_ROM_MUX5_OE_N
R1220  Q_RES  18K 1% CHIP  pkg 0402LF  page 258 : 1 = P1V8_CPU0_RT_1D_ADC ; 2 = GND
R1221  Q_RES  18K 1% CHIP  pkg 0402LF  page 258 : 1 = P1V2_AUX_ADC ; 2 = GND
R1222  Q_RES  18K 1% CHIP  pkg 0402LF  page 258 : 1 = PVDD18_S5_P0_ADC ; 2 = GND
R1223  Q_RES  18K 1% CHIP  pkg 0402LF  page 258 : 1 = P1V8_CPU1_RT_1D_ADC ; 2 = GND
R1224  Q_RES  4.7K 1% CHIP  pkg 0402LF  page 258 : 1 = PVDD_33_S5_ADC ; 2 = GND
R1225  Q_RES  18K 1% CHIP  pkg 0402LF  page 258 : 1 = PVDD18_S5_P1_ADC ; 2 = GND
R1226  Q_RES  9.09K 1% CHIP  pkg 0402LF  page 258 : 1 = P5V_AUX_ADC ; 2 = GND
R1227  Q_RES  0 5% EMPTY  pkg 0402LF  page 258 : 1 = SMB_ADC_SDA_R ; 2 = SMB_SEN_MAM_2_3V3AUX_SDA
R1228  Q_RES  0 5% EMPTY  pkg 0402LF  page 258 : 1 = SMB_ADC_SCL_R ; 2 = SMB_SEN_MAM_2_3V3AUX_SCL
R1229  Q_RES  18K 1% CHIP  pkg 0402LF  page 258 : 1 = P1V8_AUX_ADC ; 2 = GND
R1230  Q_RES  2K 1% CHIP  pkg 0402LF  page 258 : 1 = MAX11617_2_VREF ; 2 = MAX11617_2_VREF_R
R1231  Q_RES  5.11K 1% CHIP  pkg 0402LF  page 258 : 1 = P1V8_CPU0_RT_1D ; 2 = P1V8_CPU0_RT_1D_ADC
R1232  Q_RES  5.11K 1% CHIP  pkg 0402LF  page 258 : 1 = P1V2_AUX ; 2 = P1V2_AUX_ADC
R1233  Q_RES  5.11K 1% CHIP  pkg 0402LF  page 258 : 1 = PVDD18_S5_P0 ; 2 = PVDD18_S5_P0_ADC
R1234  Q_RES  5.11K 1% CHIP  pkg 0402LF  page 258 : 1 = P1V8_CPU1_RT_1D ; 2 = P1V8_CPU1_RT_1D_ADC
R1235  Q_RES  5.11K 1% CHIP  pkg 0402LF  page 258 : 1 = PVDD_33_S5 ; 2 = PVDD_33_S5_ADC
R1236  Q_RES  5.11K 1% CHIP  pkg 0402LF  page 258 : 1 = PVDD18_S5_P1 ; 2 = PVDD18_S5_P1_ADC
R1237  Q_RES  5.11K 1% CHIP  pkg 0402LF  page 258 : 1 = P1V8_AUX ; 2 = P1V8_AUX_ADC
R1238  Q_RES  18K 1% CHIP  pkg 0402LF  page 258 : 1 = P5V_AUX ; 2 = P5V_AUX_ADC
R1239  Q_RES  1K 1% EMPTY  pkg 0402LF  page 258 : 1 = P3V3_AUX ; 2 = ADC128_2_A1
R1240  Q_RES  1K 1% CHIP  pkg 0402LF  page 258 : 1 = ADC128_2_A1 ; 2 = GND
R1241  Q_RES  1K 1% EMPTY  pkg 0402LF  page 258 : 1 = P3V3_AUX ; 2 = ADC128_2_A0
R1242  Q_RES  1K 1% CHIP  pkg 0402LF  page 258 : 1 = ADC128_2_A0 ; 2 = GND
R1243  Q_RES  0 5% CHIP  pkg 0402LF  page 258 : 1 = SMB_ADC_SDA_R ; 2 = SMB_SEN_TIC_2_3V3AUX_SDA
R1244  Q_RES  0 5% CHIP  pkg 0402LF  page 258 : 1 = SMB_ADC_SCL_R ; 2 = SMB_SEN_TIC_2_3V3AUX_SCL
R1245  Q_RES  0 5% EMPTY  pkg 0402LF  page 258 : 1 = P1V2_AUX_ADC ; 2 = P1V2_AUX_ADC_MAM
R1246  Q_RES  0 5% EMPTY  pkg 0402LF  page 258 : 1 = P1V8_CPU0_RT_1D_ADC ; 2 = P1V8_CPU0_RT_1D_ADC_MAM
R1247  Q_RES  0 5% EMPTY  pkg 0402LF  page 258 : 1 = PVDD18_S5_P0_ADC ; 2 = PVDD18_S5_P0_ADC_MAM
R1248  Q_RES  0 5% EMPTY  pkg 0402LF  page 258 : 1 = PVDD_33_S5_ADC ; 2 = PVDD_33_S5_ADC_MAM
R1249  Q_RES  0 5% EMPTY  pkg 0402LF  page 258 : 1 = PVDD18_S5_P1_ADC ; 2 = PVDD18_S5_P1_ADC_MAM
R1250  Q_RES  0 5% EMPTY  pkg 0402LF  page 258 : 1 = P1V8_CPU1_RT_1D_ADC ; 2 = P1V8_CPU1_RT_1D_ADC_MAM
R1251  Q_RES  0 5% CHIP  pkg 0402LF  page 258 : 1 = P1V2_AUX_ADC ; 2 = P1V2_AUX_ADC_TIC
R1252  Q_RES  0 5% CHIP  pkg 0402LF  page 258 : 1 = P1V8_CPU0_RT_1D_ADC ; 2 = P1V8_CPU0_RT_1D_ADC_TIC
R1253  Q_RES  33 5% CHIP  pkg 0402LF  page 164 : 1 = UART_LS_EN_N ; 2 = UART_LS_EN_R_N
R1254  Q_RES  0 5% CHIP  pkg 0402LF  page 258 : 1 = PVDD18_S5_P0_ADC ; 2 = PVDD18_S5_P0_ADC_TIC
R1255  Q_RES  0 5% CHIP  pkg 0402LF  page 258 : 1 = PVDD_33_S5_ADC ; 2 = PVDD_33_S5_ADC_TIC
R1256  Q_RES  0 5% CHIP  pkg 0402LF  page 258 : 1 = PVDD18_S5_P1_ADC ; 2 = PVDD18_S5_P1_ADC_TIC
R1257  Q_RES  0 5% CHIP  pkg 0402LF  page 258 : 1 = P1V8_CPU1_RT_1D_ADC ; 2 = P1V8_CPU1_RT_1D_ADC_TIC
R1258  Q_RES  0 5% EMPTY  pkg 0402LF  page 258 : 1 = P1V8_AUX_ADC ; 2 = P1V8_AUX_ADC_MAM
R1259  Q_RES  0 5% CHIP  pkg 0402LF  page 258 : 1 = P1V8_AUX_ADC ; 2 = P1V8_AUX_ADC_TIC
R1260  Q_RES  0 5% EMPTY  pkg 0402LF  page 258 : 1 = P5V_AUX_ADC ; 2 = P5V_AUX_ADC_MAM
R1261  Q_RES  10K 5% CHIP  pkg 0402LF  page 167 : 1 = P1V8_AUX ; 2 = FM_SPD_CPU0_SWITCH_CTRL_N
R1262  Q_RES  10K 5% CHIP  pkg 0402LF  page 167 : 1 = P1V8_AUX ; 2 = BMC_JTAG_SEL
R1263  Q_RES  0 5% CHIP  pkg 0402LF  page 258 : 1 = P5V_AUX_ADC ; 2 = P5V_AUX_ADC_TIC
R1264  Q_RES  1K 1% EMPTY  pkg 0402LF  page 167 : 1 = P1V8_AUX ; 2 = BIOS_DEBUG_MODE
R1265  Q_RES  10K 5% CHIP  pkg 0402LF  page 167 : 1 = FM_BIOS_USB_RECOVERY ; 2 = GND
R1266  Q_RES  200 1% CHIP  pkg 0402LF  page 85 : 1 = P3V3_AUX ; 2 = BMC_FPGA_LED1_R_N
R1267  Q_RES  4.7K 1% EMPTY  pkg 0402LF  page 258 : 1 = P3V3_ADC128_2_VCC ; 2 = ADC128_2_VREF
R1268  Q_RES  4.7K 1% EMPTY  pkg 0402LF  page 258 : 1 = ADC128_2_VREF ; 2 = GND
R1269  Q_RES  0 5% CHIP  pkg 0402LF  page 357 : 1 = P12V_E1S_0_ADC_ALERT_R ; 2 = E1S_0_P3V3_P12V_ADC_R_ALERT
R1270  Q_RES  0 5% CHIP  pkg 0402LF  page 357 : 1 = P12V_OCP_SFF_ADC_ALERT_R ; 2 = OCP_SFF_P3V3_P12V_ADC_R_ALERT
R1271  Q_RES  0 5% CHIP  pkg 0402LF  page 357 : 1 = P12V_OCP_V3_2_ADC_ALERT_R ; 2 = OCP_V3_2_P3V3_P12V_ADC_R_ALERT
R1272  Q_RES  0 5% CHIP  pkg 0402LF  page 357 : 1 = SMB_INA230_8_3V3AUX_SCL_R ; 2 = SMB_INA230_8_3V3AUX_SCL_R1
R1273  Q_RES  0 5% CHIP  pkg 0402LF  page 357 : 1 = SMB_INA230_6_3V3AUX_SCL_R ; 2 = SMB_INA230_6_3V3AUX_SCL_R1
R1274  Q_RES  0 5% CHIP  pkg 0402LF  page 357 : 1 = SMB_INA230_7_3V3AUX_SCL_R ; 2 = SMB_INA230_7_3V3AUX_SCL_R1
R1275  Q_RES  0 5% CHIP  pkg 0402LF  page 357 : 1 = SMB_INA230_8_3V3AUX_SDA_R ; 2 = SMB_INA230_8_3V3AUX_SDA_R1
R1276  Q_RES  0 5% CHIP  pkg 0402LF  page 357 : 1 = SMB_INA230_6_3V3AUX_SDA_R ; 2 = SMB_INA230_6_3V3AUX_SDA_R1
R1277  Q_RES  0 5% CHIP  pkg 0402LF  page 357 : 1 = SMB_INA230_7_3V3AUX_SDA_R ; 2 = SMB_INA230_7_3V3AUX_SDA_R1
R1278  Q_RES  33 5% CHIP  pkg 0402LF  page 81 : 1 = FM_P1_PCC0_N ; 2 = FM_P1_PCC0_R_N
R1279  Q_RES  33 5% CHIP  pkg 0402LF  page 81 : 1 = FM_P1_PCC1_N ; 2 = FM_P1_PCC1_R_N
R1280  Q_RES  33 5% CHIP  pkg 0402LF  page 81 : 1 = FM_P0_PCC0_N ; 2 = FM_P0_PCC0_R_N
R1281  Q_RES  33 5% CHIP  pkg 0402LF  page 81 : 1 = FM_P0_PCC1_N ; 2 = FM_P0_PCC1_R_N
R1282  Q_RES  33 5% CHIP  pkg 0402LF  page 81 : 1 = FM_NCSI_OCP_SFF_R_OE ; 2 = FM_PLD_OCP_SFF_PWR_GOOD_R
R1283  Q_RES  10 1% CHIP  pkg 0402LF  page 357 : 1 = P12V_E1S_0 ; 2 = VSENSE_P12V_INA230_8_INP
R1284  Q_RES  10 1% CHIP  pkg 0402LF  page 357 : 1 = P12V_OCP_SFF ; 2 = VSENSE_P12V_INA230_6_INP
R1285  Q_RES  4.7K 5% CHIP  pkg 0402LF  page 83 : 1 = FM_P1_PCC0_N ; 2 = PVDD18_S5_P1
R1286  Q_RES  4.7K 5% CHIP  pkg 0402LF  page 83 : 1 = FM_P1_PCC1_N ; 2 = PVDD18_S5_P1
R1287  Q_RES  4.7K 5% CHIP  pkg 0402LF  page 83 : 1 = FM_P0_PCC0_N ; 2 = PVDD18_S5_P0
R1288  Q_RES  4.7K 5% CHIP  pkg 0402LF  page 83 : 1 = FM_P0_PCC1_N ; 2 = PVDD18_S5_P0
R1289  Q_RES  100K 1% CHIP  pkg 0402LF  page 132 : 1 = FB_BMC_ISOLATE ; 2 = GND
R1290  Q_RES  22 1% EMPTY  pkg 0402LF  page 132 : 1 = OCP_SFF_RBT_ARB_IN_R ; 2 = OCP_SFF_RBT_ARB_IN
R1291  Q_RES  10 1% CHIP  pkg 0402LF  page 357 : 1 = P12V_OCP_V3_2 ; 2 = VSENSE_P12V_INA230_7_INP
R1292  Q_RES  10 1% CHIP  pkg 0402LF  page 357 : 1 = P12V_E1S_0_R ; 2 = VSENSE_P12V_INA230_8_INN
R1293  Q_RES  0 5% CHIP  pkg 0402LF  page 159 : 1 = I3C_SPD_DDRAF_CPU1_SCL ; 2 = I3C_SPD_DDRAF_CPU1_LVC1_SCL
R1294  Q_RES  0 5% CHIP  pkg 0402LF  page 159 : 1 = I3C_SPD_DDRAF_CPU1_SDA ; 2 = I3C_SPD_DDRAF_CPU1_LVC1_SDA
R1295  Q_RES  0 5% CHIP  pkg 0402LF  page 159 : 1 = I3C_SPD_DDRGL_CPU1_SCL ; 2 = I3C_SPD_DDRGL_CPU1_LVC1_SCL
R1296  Q_RES  0 5% CHIP  pkg 0402LF  page 159 : 1 = I3C_SPD_DDRGL_CPU1_SDA ; 2 = I3C_SPD_DDRGL_CPU1_LVC1_SDA
R1297  Q_RES  0 5% CHIP  pkg 0402LF  page 159 : 1 = I3C_SPD_DDRAF_CPU0_SCL ; 2 = I3C_SPD_DDRAF_CPU0_LVC1_SCL
R1298  Q_RES  0 5% CHIP  pkg 0402LF  page 159 : 1 = I3C_SPD_DDRAF_CPU0_SDA ; 2 = I3C_SPD_DDRAF_CPU0_LVC1_SDA
R1299  Q_RES  0 5% CHIP  pkg 0402LF  page 159 : 1 = I3C_SPD_DDRGL_CPU0_SCL ; 2 = I3C_SPD_DDRGL_CPU0_LVC1_SCL
R1300  Q_RES  0 5% CHIP  pkg 0402LF  page 159 : 1 = I3C_SPD_DDRGL_CPU0_SDA ; 2 = I3C_SPD_DDRGL_CPU0_LVC1_SDA
R1301  Q_RES  10 1% CHIP  pkg 0402LF  page 357 : 1 = P12V_OCP_SFF_R ; 2 = VSENSE_P12V_INA230_6_INN
R1302  Q_RES  10 1% CHIP  pkg 0402LF  page 357 : 1 = P12V_OCP_V3_2_R ; 2 = VSENSE_P12V_INA230_7_INN
R1303  Q_RES  1K 1% CHIP  pkg 0402LF  page 85 : 1 = FM_SMB_RST_E1S_0_N ; 2 = P3V3_AUX
R1304  Q_RES  10K 1% CHIP  pkg 0402LF  page 83 : 1 = E1S_0_PRSNT_N ; 2 = P3V3_AUX
R1305  Q_RES  4.7K 1% EMPTY  pkg 0402LF  page 357 : 1 = GND ; 2 = INA230_8_A1
R1306  Q_RES  4.7K 1% EMPTY  pkg 0402LF  page 357 : 1 = GND ; 2 = INA230_6_A1
R1307  Q_RES  4.7K 1% EMPTY  pkg 0402LF  page 357 : 1 = GND ; 2 = INA230_7_A1
R1308  Q_RES  4.7K 1% CHIP  pkg 0402LF  page 357 : 1 = GND ; 2 = INA230_8_A0
R1309  Q_RES  4.7K 1% EMPTY  pkg 0402LF  page 357 : 1 = GND ; 2 = INA230_6_A0
R1310  Q_RES  4.7K 1% EMPTY  pkg 0402LF  page 357 : 1 = GND ; 2 = INA230_7_A0
R1311  Q_RES  33 5% CHIP  pkg 0402LF  page 155 : 1 = IRQ_WAKE_R_N ; 2 = IRQ_WAKE_N
R1312  Q_RES  0 5% CHIP  pkg 0402LF  page 252 : 1 = SMB_ADC_SDA ; 2 = SMB_ADC_SDA_R
R1313  Q_RES  4.7K 5% CHIP  pkg 0402LF  page 171 : 1 = PD_U160_EN_N ; 2 = GND
R1314  Q_RES  4.7K 5% EMPTY  pkg 0402LF  page 83 : 1 = E1S_0_P12V_EN ; 2 = P3V3_AUX
R1315  Q_RES  0 5% CHIP  pkg 0402LF  page 252 : 1 = SMB_ADC_SCL ; 2 = SMB_ADC_SCL_R
R1316  Q_RES  2.2K 5% CHIP  pkg 0402LF  page 252 : 1 = P3V3_AUX ; 2 = SMB_ADC_SCL_R
R1317  Q_RES  4.7K 1% EMPTY  pkg 0402LF  page 357 : 1 = P3V3_AUX ; 2 = INA230_8_A1
R1318  Q_RES  4.7K 5% CHIP  pkg 0402LF  page 171 : 1 = PD_U212_EN_N ; 2 = GND
R1319  Q_RES  2K 1% EMPTY  pkg 0402LF  page 151 : 1 = SMB_CPU0_CPU1_APML_SCL ; 2 = P3V3_AUX
R1320  Q_RES  4.7K 1% CHIP  pkg 0402LF  page 357 : 1 = P3V3_AUX ; 2 = INA230_6_A1
R1321  Q_RES  33 5% CHIP  pkg 0402LF  page 151 : 1 = SMB_VR_3V3STBY_SCL ; 2 = SMB_SCM_2_R1_SCL
R1322  Q_RES  4.7K 1% CHIP  pkg 0402LF  page 357 : 1 = P3V3_AUX ; 2 = INA230_7_A1
R1323  Q_RES  0.002 1% CHIP  pkg 2512LF  page 357 : 1 = P12V_E1S_0_R ; 2 = P12V_E1S_0
R1324  Q_RES  0.002 1% CHIP  pkg 2512LF  page 357 : 1 = P12V_OCP_SFF_R ; 2 = P12V_OCP_SFF
R1325  Q_RES  0.002 1% CHIP  pkg 2512LF  page 357 : 1 = P12V_OCP_V3_2_R ; 2 = P12V_OCP_V3_2
R1326  Q_RES  1K 1% EMPTY  pkg 0402LF  page 357 : 1 = P3V3_AUX ; 2 = E1S_0_P3V3_P12V_ADC_R_ALERT
R1327  Q_RES  1K 1% EMPTY  pkg 0402LF  page 357 : 1 = P3V3_AUX ; 2 = OCP_SFF_P3V3_P12V_ADC_R_ALERT
R1328  Q_RES  1K 1% EMPTY  pkg 0402LF  page 357 : 1 = P3V3_AUX ; 2 = OCP_V3_2_P3V3_P12V_ADC_R_ALERT
R1329  Q_RES  0 5% CHIP  pkg 0402LF  page 82 : 1 = E1S_0_P3V3_P12V_ADC_R_ALERT ; 2 = E1S_0_P3V3_P12V_ADC_ALERT
R1330  Q_RES  0 5% EMPTY  pkg 0402LF  page 159 : 1 = I3C_SPD_DDRAF_CPU0_BYPASS_SCL ; 2 = I3C_SPD_DDRAF_CPU0_SCL
R1331  Q_RES  0 5% EMPTY  pkg 0402LF  page 159 : 1 = I3C_SPD_DDRAF_CPU0_BYPASS_SDA ; 2 = I3C_SPD_DDRAF_CPU0_SDA
R1332  Q_RES  0 5% EMPTY  pkg 0402LF  page 159 : 1 = I3C_SPD_DDRGL_CPU0_BYPASS_SCL ; 2 = I3C_SPD_DDRGL_CPU0_SCL
R1333  Q_RES  0 5% EMPTY  pkg 0402LF  page 159 : 1 = I3C_SPD_DDRGL_CPU0_BYPASS_SDA ; 2 = I3C_SPD_DDRGL_CPU0_SDA
R1334  Q_RES  0 5% EMPTY  pkg 0402LF  page 159 : 1 = I3C_SPD_DDRAF_CPU1_BYPASS_SCL ; 2 = I3C_SPD_DDRAF_CPU1_SCL
R1335  Q_RES  0 5% EMPTY  pkg 0402LF  page 159 : 1 = I3C_SPD_DDRAF_CPU1_BYPASS_SDA ; 2 = I3C_SPD_DDRAF_CPU1_SDA
R1336  Q_RES  0 5% EMPTY  pkg 0402LF  page 159 : 1 = I3C_SPD_DDRGL_CPU1_BYPASS_SCL ; 2 = I3C_SPD_DDRGL_CPU1_SCL
R1337  Q_RES  0 5% EMPTY  pkg 0402LF  page 159 : 1 = I3C_SPD_DDRGL_CPU1_BYPASS_SDA ; 2 = I3C_SPD_DDRGL_CPU1_SDA
R1338  Q_RES  4.7K 5% CHIP  pkg 0402LF  page 84 : 1 = P3V3_AUX ; 2 = SCM_IRQ_N
R1339  Q_RES  0 5% CHIP  pkg 0402LF  page 82 : 1 = OCP_V3_2_P3V3_P12V_ADC_R_ALERT ; 2 = OCP_V3_2_P3V3_P12V_ADC_ALERT
R1340  Q_RES  0 5% CHIP  pkg 0402LF  page 82 : 1 = OCP_SFF_P3V3_P12V_ADC_ALERT ; 2 = OCP_SFF_P3V3_P12V_ADC_R_ALERT
R1341  Q_RES  2.2K 5% CHIP  pkg 0402LF  page 252 : 1 = P3V3_AUX ; 2 = SMB_ADC_SDA_R
R1342  Q_RES  10K 1% CHIP  pkg 0402LF  page 171 : 1 = FW_RECOVERY_R ; 2 = GND
R1343  Q_RES  4.7K 5% EMPTY  pkg 0402LF  page 171 : 1 = P3V3_AUX ; 2 = SCM_JTAG_MUX_S1
R1344  Q_RES  33.2 1% CHIP  pkg 0402LF  page 251 : 1 = SMB_INA230_3V3AUX_SCL ; 2 = SMB_INA230_6_3V3AUX_SCL_R
R1345  Q_RES  33.2 1% CHIP  pkg 0402LF  page 251 : 1 = SMB_INA230_3V3AUX_SDA ; 2 = SMB_INA230_6_3V3AUX_SDA_R
R1346  Q_RES  33.2 1% CHIP  pkg 0402LF  page 251 : 1 = SMB_INA230_3V3AUX_SCL ; 2 = SMB_INA230_7_3V3AUX_SCL_R
R1347  Q_RES  33.2 1% CHIP  pkg 0402LF  page 251 : 1 = SMB_INA230_3V3AUX_SDA ; 2 = SMB_INA230_7_3V3AUX_SDA_R
R1348  Q_RES  33.2 1% CHIP  pkg 0402LF  page 251 : 1 = SMB_INA230_3V3AUX_SCL ; 2 = SMB_INA230_8_3V3AUX_SCL_R
R1349  Q_RES  33.2 1% CHIP  pkg 0402LF  page 251 : 1 = SMB_INA230_3V3AUX_SDA ; 2 = SMB_INA230_8_3V3AUX_SDA_R
R1350  Q_RES  0 5% CHIP  pkg 0402LF  page 357 : 1 = INA230_8_A1 ; 2 = SMB_INA230_8_3V3AUX_SDA_R1
R1351  Q_RES  2.2K 5% CHIP  pkg 0402LF  page 83 : 1 = RST_CPU0_KBRST_R_N ; 2 = PVDD18_S5_P0
R1352  Q_RES  0 5% CHIP  pkg 0402LF  page 172 : 1 = HDT_HDR_R_TCK ; 2 = HDT_HDR_TCK
R1353  Q_RES  0 5% CHIP  pkg 0402LF  page 172 : 1 = HDT_HDR_R_TMS ; 2 = HDT_HDR_TMS
R1354  Q_RES  0 5% CHIP  pkg 0402LF  page 172 : 1 = HDT_HDR_R_TDI ; 2 = HDT_HDR_TDI
R1355  Q_RES  0 5% CHIP  pkg 0402LF  page 357 : 1 = INA230_6_A0 ; 2 = SMB_INA230_6_3V3AUX_SDA_R1
R1356  Q_RES  4.7K 5% CHIP  pkg 0402LF  page 167 : 1 = P3V3_AUX ; 2 = FM_PRSNT_CPU0_N
R1357  Q_RES  2.2K 5% CHIP  pkg 0402LF  page 167 : 1 = P3V3_AUX ; 2 = FM_PRSNT_CPU1_N
R1358  Q_RES  10K 5% EMPTY  pkg 0402LF  page 167 : 1 = P1V8_AUX ; 2 = FM_PASSWORD_CLEAR_N
R1359  Q_RES  0 5% CHIP  pkg 0402LF  page 81 : 1 = BMC_JTAG_SEL_R ; 2 = BMC_JTAG_SEL
R1360  Q_RES  0 5% CHIP  pkg 0402LF  page 357 : 1 = INA230_7_A0 ; 2 = SMB_INA230_7_3V3AUX_SCL_R1
R1361  Q_RES  4.7K 5% CHIP  pkg 0201LF  page 185 : 1 = P1V8_CPU1_RT_1D ; 2 = SMB_RT_CPU1_P0_ROM_MUX_2D_R_SDA
R1362  Q_RES  33 5% CHIP  pkg 0402LF  page 188 : 1 = PWRGD_P3V3_R1 ; 2 = PWRGD_P3V3_R2
